(kicad_pcb
	(version 20260206)
	(generator "pcbnew")
	(generator_version "10.0")
	(general
		(thickness 1.6)
		(legacy_teardrops no)
	)
	(paper "A4")
	(title_block
		(title "03242023_DA0F0TMBIJ0_F0T_Motherboard_J_brd_V01_OCP.brd")
		(comment 1 "Grand Teton / footprints 1265-1270 of 6105")
	)
	(layers
		(0 "F.Cu" signal "TOP")
		(4 "In1.Cu" signal "GND")
		(6 "In2.Cu" signal "IN1")
		(8 "In3.Cu" signal "GND1")
		(10 "In4.Cu" signal "IN2")
		(12 "In5.Cu" signal "GND2")
		(14 "In6.Cu" signal "IN3")
		(16 "In7.Cu" signal "GND3")
		(18 "In8.Cu" signal "VCC")
		(20 "In9.Cu" signal "VCC1")
		(22 "In10.Cu" signal "GND4")
		(24 "In11.Cu" signal "IN4")
		(26 "In12.Cu" signal "GND5")
		(28 "In13.Cu" signal "IN5")
		(30 "In14.Cu" signal "GND6")
		(32 "In15.Cu" signal "IN6")
		(34 "In16.Cu" signal "GND7")
		(2 "B.Cu" signal "BOTTOM")
		(9 "F.Adhes" user "F.Adhesive")
		(11 "B.Adhes" user "B.Adhesive")
		(13 "F.Paste" user "Package Geometry/Pastemask Top")
		(15 "B.Paste" user "Package Geometry/Pastemask Bottom")
		(5 "F.SilkS" user "Ref Des/Silkscreen Top")
		(7 "B.SilkS" user "Ref Des/Silkscreen Bottom")
		(1 "F.Mask" user "Board Geometry/Soldermask Top")
		(3 "B.Mask" user "Board Geometry/Soldermask Bottom")
		(17 "Dwgs.User" user "User.Drawings")
		(19 "Cmts.User" user "User.Comments")
		(21 "Eco1.User" user "User.Eco1")
		(23 "Eco2.User" user "User.Eco2")
		(25 "Edge.Cuts" user "Board Geometry/Outline")
		(27 "Margin" user)
		(31 "F.CrtYd" user "Package Geometry/Place Bound Top")
		(29 "B.CrtYd" user "Package Geometry/Place Bound Bottom")
		(35 "F.Fab" user "Ref Des/Assembly Top")
		(33 "B.Fab" user "Ref Des/Assembly Bottom")
	)
	(footprint ""
		(layer "F.Cu")
		(at 394.39088 -148.808948 -90)
		(property "Reference" "R448"
			(at 0 0 270)
			(layer "F.SilkS")
			(hide yes)
			(effects
				(font
					(size 1.27 1.27)
				)
			)
		)
		(property "Value" ""
			(at 0 0 270)
			(layer "F.Fab")
			(effects
				(font
					(size 1.27 1.27)
				)
			)
		)
		(duplicate_pad_numbers_are_jumpers no)
		(fp_line
			(start -0.7874 0.4064)
			(end -0.7874 -0.4064)
			(stroke
				(width 0.1524)
				(type default)
			)
			(layer "F.SilkS")
		)
		(fp_line
			(start 0.7874 0.4064)
			(end -0.7874 0.4064)
			(stroke
				(width 0.1524)
				(type default)
			)
			(layer "F.SilkS")
		)
		(fp_line
			(start -0.7874 -0.4064)
			(end 0.7874 -0.4064)
			(stroke
				(width 0.1524)
				(type default)
			)
			(layer "F.SilkS")
		)
		(fp_line
			(start 0.7874 -0.4064)
			(end 0.7874 0.4064)
			(stroke
				(width 0.1524)
				(type default)
			)
			(layer "F.SilkS")
		)
		(fp_line
			(start -0.67945 0.3048)
			(end -0.67945 -0.305054)
			(stroke
				(width 0.1)
				(type default)
			)
			(layer "F.Fab")
		)
		(fp_line
			(start -0.12065 0.3048)
			(end -0.67945 0.3048)
			(stroke
				(width 0.1)
				(type default)
			)
			(layer "F.Fab")
		)
		(fp_line
			(start 0.120396 0.3048)
			(end 0.120396 0.2794)
			(stroke
				(width 0.1)
				(type default)
			)
			(layer "F.Fab")
		)
		(fp_line
			(start 0.67945 0.3048)
			(end 0.120396 0.3048)
			(stroke
				(width 0.1)
				(type default)
			)
			(layer "F.Fab")
		)
		(fp_line
			(start -0.12065 0.2794)
			(end -0.12065 0.3048)
			(stroke
				(width 0.1)
				(type default)
			)
			(layer "F.Fab")
		)
		(fp_line
			(start 0.120396 0.2794)
			(end -0.12065 0.2794)
			(stroke
				(width 0.1)
				(type default)
			)
			(layer "F.Fab")
		)
		(fp_line
			(start -0.12065 -0.2794)
			(end 0.12065 -0.2794)
			(stroke
				(width 0.1)
				(type default)
			)
			(layer "F.Fab")
		)
		(fp_line
			(start 0.12065 -0.2794)
			(end 0.12065 -0.3048)
			(stroke
				(width 0.1)
				(type default)
			)
			(layer "F.Fab")
		)
		(fp_line
			(start 0.12065 -0.3048)
			(end 0.67945 -0.3048)
			(stroke
				(width 0.1)
				(type default)
			)
			(layer "F.Fab")
		)
		(fp_line
			(start 0.67945 -0.3048)
			(end 0.67945 0.3048)
			(stroke
				(width 0.1)
				(type default)
			)
			(layer "F.Fab")
		)
		(fp_line
			(start -0.67945 -0.305054)
			(end -0.12065 -0.305054)
			(stroke
				(width 0.1)
				(type default)
			)
			(layer "F.Fab")
		)
		(fp_line
			(start -0.12065 -0.305054)
			(end -0.12065 -0.2794)
			(stroke
				(width 0.1)
				(type default)
			)
			(layer "F.Fab")
		)
		(pad "1" smd circle
			(at -0.40005 0 270)
			(size 0 0)
			(layers "F.Cu" "F.Mask" "F.Paste")
			(net "SMB_S3M_CPU0_3V3AUX_SCL")
		)
		(pad "2" smd circle
			(at 0.40005 0 270)
			(size 0 0)
			(layers "F.Cu" "F.Mask" "F.Paste")
			(net "SMB_S3M_CPU1_3V3AUX_SCL")
		)
	)
	(footprint ""
		(layer "F.Cu")
		(at 420.124128 -175.135286 -90)
		(property "Reference" "PC192_P0_2"
			(at 0 0 270)
			(layer "F.SilkS")
			(hide yes)
			(effects
				(font
					(size 1.27 1.27)
				)
			)
		)
		(property "Value" ""
			(at 0 0 270)
			(layer "F.Fab")
			(effects
				(font
					(size 1.27 1.27)
				)
			)
		)
		(duplicate_pad_numbers_are_jumpers no)
		(fp_line
			(start -0.7874 0.4064)
			(end -0.7874 -0.4064)
			(stroke
				(width 0.1524)
				(type default)
			)
			(layer "F.SilkS")
		)
		(fp_line
			(start 0.7874 0.4064)
			(end -0.7874 0.4064)
			(stroke
				(width 0.1524)
				(type default)
			)
			(layer "F.SilkS")
		)
		(fp_line
			(start -0.7874 -0.4064)
			(end 0.7874 -0.4064)
			(stroke
				(width 0.1524)
				(type default)
			)
			(layer "F.SilkS")
		)
		(fp_line
			(start 0.7874 -0.4064)
			(end 0.7874 0.4064)
			(stroke
				(width 0.1524)
				(type default)
			)
			(layer "F.SilkS")
		)
		(fp_line
			(start -0.67945 0.3048)
			(end -0.67945 -0.305054)
			(stroke
				(width 0.1)
				(type default)
			)
			(layer "F.Fab")
		)
		(fp_line
			(start -0.12065 0.3048)
			(end -0.67945 0.3048)
			(stroke
				(width 0.1)
				(type default)
			)
			(layer "F.Fab")
		)
		(fp_line
			(start 0.120396 0.3048)
			(end 0.120396 0.2794)
			(stroke
				(width 0.1)
				(type default)
			)
			(layer "F.Fab")
		)
		(fp_line
			(start 0.67945 0.3048)
			(end 0.120396 0.3048)
			(stroke
				(width 0.1)
				(type default)
			)
			(layer "F.Fab")
		)
		(fp_line
			(start -0.12065 0.2794)
			(end -0.12065 0.3048)
			(stroke
				(width 0.1)
				(type default)
			)
			(layer "F.Fab")
		)
		(fp_line
			(start 0.120396 0.2794)
			(end -0.12065 0.2794)
			(stroke
				(width 0.1)
				(type default)
			)
			(layer "F.Fab")
		)
		(fp_line
			(start -0.12065 -0.2794)
			(end 0.12065 -0.2794)
			(stroke
				(width 0.1)
				(type default)
			)
			(layer "F.Fab")
		)
		(fp_line
			(start 0.12065 -0.2794)
			(end 0.12065 -0.3048)
			(stroke
				(width 0.1)
				(type default)
			)
			(layer "F.Fab")
		)
		(fp_line
			(start 0.12065 -0.3048)
			(end 0.67945 -0.3048)
			(stroke
				(width 0.1)
				(type default)
			)
			(layer "F.Fab")
		)
		(fp_line
			(start 0.67945 -0.3048)
			(end 0.67945 0.3048)
			(stroke
				(width 0.1)
				(type default)
			)
			(layer "F.Fab")
		)
		(fp_line
			(start -0.67945 -0.305054)
			(end -0.12065 -0.305054)
			(stroke
				(width 0.1)
				(type default)
			)
			(layer "F.Fab")
		)
		(fp_line
			(start -0.12065 -0.305054)
			(end -0.12065 -0.2794)
			(stroke
				(width 0.1)
				(type default)
			)
			(layer "F.Fab")
		)
		(pad "1" smd circle
			(at -0.40005 0 270)
			(size 0 0)
			(layers "F.Cu" "F.Mask" "F.Paste")
			(net "SW_P12V_PVCCINFAON_CPU0_FLT")
		)
		(pad "2" smd circle
			(at 0.40005 0 270)
			(size 0 0)
			(layers "F.Cu" "F.Mask" "F.Paste")
			(net "GND")
		)
	)
	(footprint ""
		(layer "F.Cu")
		(at 350.78416 -358.452674 180)
		(property "Reference" "C3269"
			(at 0 0 180)
			(layer "F.SilkS")
			(hide yes)
			(effects
				(font
					(size 1.27 1.27)
				)
			)
		)
		(property "Value" ""
			(at 0 0 180)
			(layer "F.Fab")
			(effects
				(font
					(size 1.27 1.27)
				)
			)
		)
		(duplicate_pad_numbers_are_jumpers no)
		(fp_line
			(start 0.7874 0.4064)
			(end -0.7874 0.4064)
			(stroke
				(width 0.1524)
				(type default)
			)
			(layer "F.SilkS")
		)
		(fp_line
			(start 0.7874 -0.4064)
			(end 0.7874 0.4064)
			(stroke
				(width 0.1524)
				(type default)
			)
			(layer "F.SilkS")
		)
		(fp_line
			(start -0.7874 0.4064)
			(end -0.7874 -0.4064)
			(stroke
				(width 0.1524)
				(type default)
			)
			(layer "F.SilkS")
		)
		(fp_line
			(start -0.7874 -0.4064)
			(end 0.7874 -0.4064)
			(stroke
				(width 0.1524)
				(type default)
			)
			(layer "F.SilkS")
		)
		(fp_line
			(start 0.67945 0.3048)
			(end 0.120396 0.3048)
			(stroke
				(width 0.1)
				(type default)
			)
			(layer "F.Fab")
		)
		(fp_line
			(start 0.67945 -0.3048)
			(end 0.67945 0.3048)
			(stroke
				(width 0.1)
				(type default)
			)
			(layer "F.Fab")
		)
		(fp_line
			(start 0.12065 -0.2794)
			(end 0.12065 -0.3048)
			(stroke
				(width 0.1)
				(type default)
			)
			(layer "F.Fab")
		)
		(fp_line
			(start 0.12065 -0.3048)
			(end 0.67945 -0.3048)
			(stroke
				(width 0.1)
				(type default)
			)
			(layer "F.Fab")
		)
		(fp_line
			(start 0.120396 0.3048)
			(end 0.120396 0.2794)
			(stroke
				(width 0.1)
				(type default)
			)
			(layer "F.Fab")
		)
		(fp_line
			(start 0.120396 0.2794)
			(end -0.12065 0.2794)
			(stroke
				(width 0.1)
				(type default)
			)
			(layer "F.Fab")
		)
		(fp_line
			(start -0.12065 0.3048)
			(end -0.67945 0.3048)
			(stroke
				(width 0.1)
				(type default)
			)
			(layer "F.Fab")
		)
		(fp_line
			(start -0.12065 0.2794)
			(end -0.12065 0.3048)
			(stroke
				(width 0.1)
				(type default)
			)
			(layer "F.Fab")
		)
		(fp_line
			(start -0.12065 -0.2794)
			(end 0.12065 -0.2794)
			(stroke
				(width 0.1)
				(type default)
			)
			(layer "F.Fab")
		)
		(fp_line
			(start -0.12065 -0.305054)
			(end -0.12065 -0.2794)
			(stroke
				(width 0.1)
				(type default)
			)
			(layer "F.Fab")
		)
		(fp_line
			(start -0.67945 0.3048)
			(end -0.67945 -0.305054)
			(stroke
				(width 0.1)
				(type default)
			)
			(layer "F.Fab")
		)
		(fp_line
			(start -0.67945 -0.305054)
			(end -0.12065 -0.305054)
			(stroke
				(width 0.1)
				(type default)
			)
			(layer "F.Fab")
		)
		(pad "1" smd circle
			(at -0.40005 0 180)
			(size 0 0)
			(layers "F.Cu" "F.Mask" "F.Paste")
			(net "PWRGD_PVCCFA_EHV_FIVRA_CPU0_R")
		)
		(pad "2" smd circle
			(at 0.40005 0 180)
			(size 0 0)
			(layers "F.Cu" "F.Mask" "F.Paste")
			(net "GND")
		)
	)
	(footprint ""
		(layer "F.Cu")
		(at 378.338842 -341.729822 90)
		(property "Reference" "PR1771"
			(at 0 0 90)
			(layer "F.SilkS")
			(hide yes)
			(effects
				(font
					(size 1.27 1.27)
				)
			)
		)
		(property "Value" ""
			(at 0 0 90)
			(layer "F.Fab")
			(effects
				(font
					(size 1.27 1.27)
				)
			)
		)
		(duplicate_pad_numbers_are_jumpers no)
		(fp_line
			(start 0.7874 -0.4064)
			(end 0.7874 0.4064)
			(stroke
				(width 0.1524)
				(type default)
			)
			(layer "F.SilkS")
		)
		(fp_line
			(start -0.7874 -0.4064)
			(end 0.7874 -0.4064)
			(stroke
				(width 0.1524)
				(type default)
			)
			(layer "F.SilkS")
		)
		(fp_line
			(start 0.7874 0.4064)
			(end -0.7874 0.4064)
			(stroke
				(width 0.1524)
				(type default)
			)
			(layer "F.SilkS")
		)
		(fp_line
			(start -0.7874 0.4064)
			(end -0.7874 -0.4064)
			(stroke
				(width 0.1524)
				(type default)
			)
			(layer "F.SilkS")
		)
		(fp_line
			(start -0.12065 -0.305054)
			(end -0.12065 -0.2794)
			(stroke
				(width 0.1)
				(type default)
			)
			(layer "F.Fab")
		)
		(fp_line
			(start -0.67945 -0.305054)
			(end -0.12065 -0.305054)
			(stroke
				(width 0.1)
				(type default)
			)
			(layer "F.Fab")
		)
		(fp_line
			(start 0.67945 -0.3048)
			(end 0.67945 0.3048)
			(stroke
				(width 0.1)
				(type default)
			)
			(layer "F.Fab")
		)
		(fp_line
			(start 0.12065 -0.3048)
			(end 0.67945 -0.3048)
			(stroke
				(width 0.1)
				(type default)
			)
			(layer "F.Fab")
		)
		(fp_line
			(start 0.12065 -0.2794)
			(end 0.12065 -0.3048)
			(stroke
				(width 0.1)
				(type default)
			)
			(layer "F.Fab")
		)
		(fp_line
			(start -0.12065 -0.2794)
			(end 0.12065 -0.2794)
			(stroke
				(width 0.1)
				(type default)
			)
			(layer "F.Fab")
		)
		(fp_line
			(start 0.120396 0.2794)
			(end -0.12065 0.2794)
			(stroke
				(width 0.1)
				(type default)
			)
			(layer "F.Fab")
		)
		(fp_line
			(start -0.12065 0.2794)
			(end -0.12065 0.3048)
			(stroke
				(width 0.1)
				(type default)
			)
			(layer "F.Fab")
		)
		(fp_line
			(start 0.67945 0.3048)
			(end 0.120396 0.3048)
			(stroke
				(width 0.1)
				(type default)
			)
			(layer "F.Fab")
		)
		(fp_line
			(start 0.120396 0.3048)
			(end 0.120396 0.2794)
			(stroke
				(width 0.1)
				(type default)
			)
			(layer "F.Fab")
		)
		(fp_line
			(start -0.12065 0.3048)
			(end -0.67945 0.3048)
			(stroke
				(width 0.1)
				(type default)
			)
			(layer "F.Fab")
		)
		(fp_line
			(start -0.67945 0.3048)
			(end -0.67945 -0.305054)
			(stroke
				(width 0.1)
				(type default)
			)
			(layer "F.Fab")
		)
		(pad "1" smd circle
			(at -0.40005 0 90)
			(size 0 0)
			(layers "F.Cu" "F.Mask" "F.Paste")
			(net "SW_PVCCIN_CPU0_BOOT5")
		)
		(pad "2" smd circle
			(at 0.40005 0 90)
			(size 0 0)
			(layers "F.Cu" "F.Mask" "F.Paste")
			(net "SW_PVCCIN_CPU0_BOOT5_R")
		)
	)
	(footprint ""
		(layer "F.Cu")
		(at 71.380096 -70.78599)
		(property "Reference" "D68"
			(at -37.474906 50.178462 90)
			(unlocked yes)
			(layer "F.SilkS")
			(effects
				(font
					(size 0.635 0.4064)
					(thickness 0.1524)
				)
				(justify left)
			)
		)
		(property "Value" ""
			(at 0 0 0)
			(layer "F.Fab")
			(effects
				(font
					(size 1.27 1.27)
				)
			)
		)
		(duplicate_pad_numbers_are_jumpers no)
		(fp_line
			(start -0.90678 0.4826)
			(end -0.90678 -0.4699)
			(stroke
				(width 0.1524)
				(type default)
			)
			(layer "F.SilkS")
		)
		(fp_line
			(start -0.89408 -0.4826)
			(end 0.90678 -0.4826)
			(stroke
				(width 0.1524)
				(type default)
			)
			(layer "F.SilkS")
		)
		(fp_line
			(start -0.79248 -0.4826)
			(end 1.03378 -0.4826)
			(stroke
				(width 0.1524)
				(type default)
			)
			(layer "F.SilkS")
		)
		(fp_line
			(start -0.64008 -0.4826)
			(end 1.16078 -0.4826)
			(stroke
				(width 0.1524)
				(type default)
			)
			(layer "F.SilkS")
		)
		(fp_line
			(start 0.90678 -0.4826)
			(end 0.90678 0.4826)
			(stroke
				(width 0.1524)
				(type default)
			)
			(layer "F.SilkS")
		)
		(fp_line
			(start 0.90678 0.4826)
			(end -0.90678 0.4826)
			(stroke
				(width 0.1524)
				(type default)
			)
			(layer "F.SilkS")
		)
		(fp_line
			(start 1.03378 -0.4826)
			(end 1.03378 0.4826)
			(stroke
				(width 0.1524)
				(type default)
			)
			(layer "F.SilkS")
		)
		(fp_line
			(start 1.03378 0.4826)
			(end -0.79248 0.4826)
			(stroke
				(width 0.1524)
				(type default)
			)
			(layer "F.SilkS")
		)
		(fp_line
			(start 1.16078 -0.4826)
			(end 1.16078 0.4826)
			(stroke
				(width 0.1524)
				(type default)
			)
			(layer "F.SilkS")
		)
		(fp_line
			(start 1.16078 0.4826)
			(end -0.64008 0.4826)
			(stroke
				(width 0.1524)
				(type default)
			)
			(layer "F.SilkS")
		)
		(fp_line
			(start -0.499872 -0.249936)
			(end 0.499872 -0.249936)
			(stroke
				(width 0.1)
				(type default)
			)
			(layer "F.Fab")
		)
		(fp_line
			(start -0.499872 0.249936)
			(end -0.499872 -0.249936)
			(stroke
				(width 0.1)
				(type default)
			)
			(layer "F.Fab")
		)
		(fp_line
			(start 0.499872 -0.249936)
			(end 0.499872 0.249936)
			(stroke
				(width 0.1)
				(type default)
			)
			(layer "F.Fab")
		)
		(fp_line
			(start 0.499872 0.249936)
			(end -0.499872 0.249936)
			(stroke
				(width 0.1)
				(type default)
			)
			(layer "F.Fab")
		)
		(pad "A" smd rect
			(at -0.47498 0)
			(size 0.6096 0.7112)
			(layers "F.Cu" "F.Mask" "F.Paste")
			(net "LED_RST_PLD_CPU0_DRAM_GH_N")
		)
		(pad "C" smd rect
			(at 0.47498 0)
			(size 0.6096 0.7112)
			(layers "F.Cu" "F.Mask" "F.Paste")
			(net "LED_RST_PLD_CPU0_DRAM_GH_N_D")
		)
	)
	(footprint ""
		(layer "F.Cu")
		(at 27.0383 -131.55295)
		(property "Reference" "R2568"
			(at 0 0 0)
			(layer "F.SilkS")
			(hide yes)
			(effects
				(font
					(size 1.27 1.27)
				)
			)
		)
		(property "Value" ""
			(at 0 0 0)
			(layer "F.Fab")
			(effects
				(font
					(size 1.27 1.27)
				)
			)
		)
		(duplicate_pad_numbers_are_jumpers no)
		(fp_line
			(start -0.7874 -0.4064)
			(end 0.7874 -0.4064)
			(stroke
				(width 0.1524)
				(type default)
			)
			(layer "F.SilkS")
		)
		(fp_line
			(start -0.7874 0.4064)
			(end -0.7874 -0.4064)
			(stroke
				(width 0.1524)
				(type default)
			)
			(layer "F.SilkS")
		)
		(fp_line
			(start 0.7874 -0.4064)
			(end 0.7874 0.4064)
			(stroke
				(width 0.1524)
				(type default)
			)
			(layer "F.SilkS")
		)
		(fp_line
			(start 0.7874 0.4064)
			(end -0.7874 0.4064)
			(stroke
				(width 0.1524)
				(type default)
			)
			(layer "F.SilkS")
		)
		(fp_line
			(start -0.67945 -0.305054)
			(end -0.12065 -0.305054)
			(stroke
				(width 0.1)
				(type default)
			)
			(layer "F.Fab")
		)
		(fp_line
			(start -0.67945 0.3048)
			(end -0.67945 -0.305054)
			(stroke
				(width 0.1)
				(type default)
			)
			(layer "F.Fab")
		)
		(fp_line
			(start -0.12065 -0.305054)
			(end -0.12065 -0.2794)
			(stroke
				(width 0.1)
				(type default)
			)
			(layer "F.Fab")
		)
		(fp_line
			(start -0.12065 -0.2794)
			(end 0.12065 -0.2794)
			(stroke
				(width 0.1)
				(type default)
			)
			(layer "F.Fab")
		)
		(fp_line
			(start -0.12065 0.2794)
			(end -0.12065 0.3048)
			(stroke
				(width 0.1)
				(type default)
			)
			(layer "F.Fab")
		)
		(fp_line
			(start -0.12065 0.3048)
			(end -0.67945 0.3048)
			(stroke
				(width 0.1)
				(type default)
			)
			(layer "F.Fab")
		)
		(fp_line
			(start 0.120396 0.2794)
			(end -0.12065 0.2794)
			(stroke
				(width 0.1)
				(type default)
			)
			(layer "F.Fab")
		)
		(fp_line
			(start 0.120396 0.3048)
			(end 0.120396 0.2794)
			(stroke
				(width 0.1)
				(type default)
			)
			(layer "F.Fab")
		)
		(fp_line
			(start 0.12065 -0.3048)
			(end 0.67945 -0.3048)
			(stroke
				(width 0.1)
				(type default)
			)
			(layer "F.Fab")
		)
		(fp_line
			(start 0.12065 -0.2794)
			(end 0.12065 -0.3048)
			(stroke
				(width 0.1)
				(type default)
			)
			(layer "F.Fab")
		)
		(fp_line
			(start 0.67945 -0.3048)
			(end 0.67945 0.3048)
			(stroke
				(width 0.1)
				(type default)
			)
			(layer "F.Fab")
		)
		(fp_line
			(start 0.67945 0.3048)
			(end 0.120396 0.3048)
			(stroke
				(width 0.1)
				(type default)
			)
			(layer "F.Fab")
		)
		(pad "1" smd circle
			(at -0.40005 0)
			(size 0 0)
			(layers "F.Cu" "F.Mask" "F.Paste")
			(net "P3V3_AUX")
		)
		(pad "2" smd circle
			(at 0.40005 0)
			(size 0 0)
			(layers "F.Cu" "F.Mask" "F.Paste")
			(net "PVCCINFAON_CPU1_VR_FAULT")
		)
	)
)
